# BASEBOARD_FAB2 (Tioga Pass) — schematic netlist excerpt (pin names and nets, part order shuffled) for the footprints in the layout excerpt that follows; sources: Cadence DE-HDL packaged netlist, KiCad conversion of Wiwynn_Tioga_Pass_MB.brd

C1G28  CAP  1.0UF 16V 10% X6S  pkg 0402  page 224 : A = VR_PVDDQ_GHJ_PH2_VCIN ; B = GND
R4D65  RES  33.2 1% CHIP  pkg 0402  page 201 : A = PWRGD_PVSA_CPU0_R ; B = PWRGD_PVSA_CPU0
C8G6  CAP  0.22UF 16V 10% X7R  pkg 0402  page 105 : A = P3E_CPU0_PE2_SS_TXN<2> ; B = P3E_CPU0_PE2_SS_C_TXN<2>

(kicad_pcb
	(version 20260206)
	(generator "pcbnew")
	(generator_version "10.0")
	(general
		(thickness 1.6)
		(legacy_teardrops no)
	)
	(paper "A4")
	(title_block
		(title "Wiwynn_Tioga_Pass_MB.brd")
		(comment 1 "Tioga Pass / footprints 1171-1173 of 4770")
	)
	(layers
		(0 "F.Cu" signal "TOP")
		(4 "In1.Cu" signal "L2GND")
		(6 "In2.Cu" signal "L3")
		(8 "In3.Cu" signal "L4GND")
		(10 "In4.Cu" signal "L5")
		(12 "In5.Cu" signal "L6GND")
		(14 "In6.Cu" signal "L7VCC")
		(16 "In7.Cu" signal "L8VCC")
		(18 "In8.Cu" signal "L9GND")
		(20 "In9.Cu" signal "L10")
		(22 "In10.Cu" signal "L11GND")
		(24 "In11.Cu" signal "L12")
		(26 "In12.Cu" signal "L13GND")
		(2 "B.Cu" signal "BOTTOM")
		(9 "F.Adhes" user "F.Adhesive")
		(11 "B.Adhes" user "B.Adhesive")
		(13 "F.Paste" user "Package Geometry/Pastemask Top")
		(15 "B.Paste" user "Package Geometry/Pastemask Bottom")
		(5 "F.SilkS" user "Ref Des/Silkscreen Top")
		(7 "B.SilkS" user "Ref Des/Silkscreen Bottom")
		(1 "F.Mask" user "Board Geometry/Soldermask Top")
		(3 "B.Mask" user "Board Geometry/Soldermask Bottom")
		(17 "Dwgs.User" user "User.Drawings")
		(19 "Cmts.User" user "User.Comments")
		(21 "Eco1.User" user "User.Eco1")
		(23 "Eco2.User" user "User.Eco2")
		(25 "Edge.Cuts" user "Board Geometry/Outline")
		(27 "Margin" user)
		(31 "F.CrtYd" user "Package Geometry/Place Bound Top")
		(29 "B.CrtYd" user "Package Geometry/Place Bound Bottom")
		(35 "F.Fab" user "Ref Des/Assembly Top")
		(33 "B.Fab" user "Ref Des/Assembly Bottom")
	)
	(footprint ""
		(layer "F.Cu")
		(at 182.118 -65.024)
		(property "Reference" "R4D65"
			(at 0 0 0)
			(layer "F.SilkS")
			(hide yes)
			(effects
				(font
					(size 1.27 1.27)
				)
			)
		)
		(property "Value" ""
			(at 0 0 0)
			(layer "F.Fab")
			(effects
				(font
					(size 1.27 1.27)
				)
			)
		)
		(duplicate_pad_numbers_are_jumpers no)
		(fp_poly
			(pts
				(xy -0.2794 -0.1016) (xy 0.2794 -0.1016) (xy 0.2794 0.9906) (xy -0.2794 0.9906)
			)
			(stroke
				(width 0)
				(type default)
			)
			(fill no)
			(layer "F.CrtYd")
		)
		(fp_line
			(start -0.2794 -0.1016)
			(end -0.2794 0.9906)
			(stroke
				(width 0.1)
				(type default)
			)
			(layer "F.Fab")
		)
		(fp_line
			(start -0.2794 0.9906)
			(end 0.2794 0.9906)
			(stroke
				(width 0.1)
				(type default)
			)
			(layer "F.Fab")
		)
		(fp_line
			(start 0.2794 -0.1016)
			(end -0.2794 -0.1016)
			(stroke
				(width 0.1)
				(type default)
			)
			(layer "F.Fab")
		)
		(fp_line
			(start 0.2794 0.9906)
			(end 0.2794 -0.1016)
			(stroke
				(width 0.1)
				(type default)
			)
			(layer "F.Fab")
		)
		(pad "1" smd rect
			(at 0 0)
			(size 0.508 0.508)
			(layers "F.Cu" "F.Mask" "F.Paste")
			(net "PWRGD_PVSA_CPU0_R")
		)
		(pad "2" smd rect
			(at 0 0.889)
			(size 0.508 0.508)
			(layers "F.Cu" "F.Mask" "F.Paste")
			(net "PWRGD_PVSA_CPU0")
		)
		(zone
			(layer "F.Cu")
			(hatch none 0.5)
			(connect_pads
				(clearance 0)
			)
			(min_thickness 0.25)
			(keepout
				(tracks allowed)
				(vias not_allowed)
				(pads allowed)
				(copperpour not_allowed)
				(footprints allowed)
			)
			(placement
				(enabled no)
				(sheetname "")
			)
			(fill
				(thermal_gap 0.5)
				(thermal_bridge_width 0.5)
				(island_removal_mode 0)
			)
			(polygon
				(pts
					(xy 181.864 -64.77) (xy 182.372 -64.77) (xy 182.372 -64.389) (xy 181.864 -64.389)
				)
			)
		)
		(zone
			(layer "F.Cu")
			(hatch none 0.5)
			(connect_pads
				(clearance 0)
			)
			(min_thickness 0.25)
			(keepout
				(tracks not_allowed)
				(vias allowed)
				(pads allowed)
				(copperpour not_allowed)
				(footprints allowed)
			)
			(placement
				(enabled no)
				(sheetname "")
			)
			(fill
				(thermal_gap 0.5)
				(thermal_bridge_width 0.5)
				(island_removal_mode 0)
			)
			(polygon
				(pts
					(xy 181.864 -64.389) (xy 182.372 -64.389) (xy 182.372 -64.77) (xy 181.864 -64.77)
				)
			)
		)
	)
	(footprint ""
		(layer "F.Cu")
		(at 3.384042 -13.599414 -90)
		(property "Reference" "C1G28"
			(at 0 0 270)
			(layer "F.SilkS")
			(hide yes)
			(effects
				(font
					(size 1.27 1.27)
				)
			)
		)
		(property "Value" ""
			(at 0 0 270)
			(layer "F.Fab")
			(effects
				(font
					(size 1.27 1.27)
				)
			)
		)
		(duplicate_pad_numbers_are_jumpers no)
		(fp_poly
			(pts
				(xy 0.3048 -0.1016) (xy 0.3048 0.9906) (xy -0.3048 0.9906) (xy -0.3048 -0.1016)
			)
			(stroke
				(width 0)
				(type default)
			)
			(fill no)
			(layer "F.CrtYd")
		)
		(fp_line
			(start -0.3048 0.9906)
			(end 0.3048 0.9906)
			(stroke
				(width 0.1)
				(type default)
			)
			(layer "F.Fab")
		)
		(fp_line
			(start 0.3048 0.9906)
			(end 0.3048 -0.1016)
			(stroke
				(width 0.1)
				(type default)
			)
			(layer "F.Fab")
		)
		(fp_line
			(start -0.3048 -0.1016)
			(end -0.3048 0.9906)
			(stroke
				(width 0.1)
				(type default)
			)
			(layer "F.Fab")
		)
		(fp_line
			(start 0.3048 -0.1016)
			(end -0.3048 -0.1016)
			(stroke
				(width 0.1)
				(type default)
			)
			(layer "F.Fab")
		)
		(pad "1" smd rect
			(at 0 0 270)
			(size 0.508 0.508)
			(layers "F.Cu" "F.Mask" "F.Paste")
			(net "VR_PVDDQ_GHJ_PH2_VCIN")
		)
		(pad "2" smd rect
			(at 0 0.889 270)
			(size 0.508 0.508)
			(layers "F.Cu" "F.Mask" "F.Paste")
			(net "GND")
		)
		(zone
			(layer "F.Cu")
			(hatch none 0.5)
			(connect_pads
				(clearance 0)
			)
			(min_thickness 0.25)
			(keepout
				(tracks not_allowed)
				(vias allowed)
				(pads allowed)
				(copperpour not_allowed)
				(footprints allowed)
			)
			(placement
				(enabled no)
				(sheetname "")
			)
			(fill
				(thermal_gap 0.5)
				(thermal_bridge_width 0.5)
				(island_removal_mode 0)
			)
			(polygon
				(pts
					(xy 2.749042 -13.853414) (xy 2.749042 -13.345414) (xy 3.130042 -13.345414) (xy 3.130042 -13.853414)
				)
			)
		)
		(zone
			(layer "F.Cu")
			(hatch none 0.5)
			(connect_pads
				(clearance 0)
			)
			(min_thickness 0.25)
			(keepout
				(tracks allowed)
				(vias not_allowed)
				(pads allowed)
				(copperpour not_allowed)
				(footprints allowed)
			)
			(placement
				(enabled no)
				(sheetname "")
			)
			(fill
				(thermal_gap 0.5)
				(thermal_bridge_width 0.5)
				(island_removal_mode 0)
			)
			(polygon
				(pts
					(xy 3.130042 -13.853414) (xy 3.130042 -13.345414) (xy 2.749042 -13.345414) (xy 2.749042 -13.853414)
				)
			)
		)
	)
	(footprint ""
		(layer "F.Cu")
		(at 406.120092 -10.917936)
		(property "Reference" "C8G6"
			(at 0 0 0)
			(layer "F.SilkS")
			(hide yes)
			(effects
				(font
					(size 1.27 1.27)
				)
			)
		)
		(property "Value" ""
			(at 0 0 0)
			(layer "F.Fab")
			(effects
				(font
					(size 1.27 1.27)
				)
			)
		)
		(duplicate_pad_numbers_are_jumpers no)
		(fp_rect
			(start -0.3048 0.9906)
			(end 0.3048 -0.1016)
			(stroke
				(width 0)
				(type default)
			)
			(fill no)
			(layer "F.CrtYd")
		)
		(fp_line
			(start -0.3048 -0.1016)
			(end -0.3048 0.9906)
			(stroke
				(width 0.1)
				(type default)
			)
			(layer "F.Fab")
		)
		(fp_line
			(start -0.3048 0.9906)
			(end 0.3048 0.9906)
			(stroke
				(width 0.1)
				(type default)
			)
			(layer "F.Fab")
		)
		(fp_line
			(start 0.3048 -0.1016)
			(end -0.3048 -0.1016)
			(stroke
				(width 0.1)
				(type default)
			)
			(layer "F.Fab")
		)
		(fp_line
			(start 0.3048 0.9906)
			(end 0.3048 -0.1016)
			(stroke
				(width 0.1)
				(type default)
			)
			(layer "F.Fab")
		)
		(pad "1" smd rect
			(at 0 0)
			(size 0.508 0.508)
			(layers "F.Cu" "F.Mask" "F.Paste")
			(net "P3E_CPU0_PE2_SS_TXN<2>")
		)
		(pad "2" smd rect
			(at 0 0.889)
			(size 0.508 0.508)
			(layers "F.Cu" "F.Mask" "F.Paste")
			(net "P3E_CPU0_PE2_SS_C_TXN<2>")
		)
		(zone
			(layer "F.Cu")
			(hatch none 0.5)
			(connect_pads
				(clearance 0)
			)
			(min_thickness 0.25)
			(keepout
				(tracks allowed)
				(vias not_allowed)
				(pads allowed)
				(copperpour not_allowed)
				(footprints allowed)
			)
			(placement
				(enabled no)
				(sheetname "")
			)
			(fill
				(thermal_gap 0.5)
				(thermal_bridge_width 0.5)
				(island_removal_mode 0)
			)
			(polygon
				(pts
					(xy 405.866092 -10.282936) (xy 406.374092 -10.282936) (xy 406.374092 -10.663936) (xy 405.866092 -10.663936)
				)
			)
		)
		(zone
			(layer "F.Cu")
			(hatch none 0.5)
			(connect_pads
				(clearance 0)
			)
			(min_thickness 0.25)
			(keepout
				(tracks not_allowed)
				(vias allowed)
				(pads allowed)
				(copperpour not_allowed)
				(footprints allowed)
			)
			(placement
				(enabled no)
				(sheetname "")
			)
			(fill
				(thermal_gap 0.5)
				(thermal_bridge_width 0.5)
				(island_removal_mode 0)
			)
			(polygon
				(pts
					(xy 405.866092 -10.282936) (xy 406.374092 -10.282936) (xy 406.374092 -10.663936) (xy 405.866092 -10.663936)
				)
			)
		)
	)
)
